# T6G (Grand Teton) — schematic netlist excerpt (pin names and nets, part order shuffled) for the footprints in the layout excerpt that follows; sources: Cadence DE-HDL packaged netlist, KiCad conversion of 04192023_DAF0TMB3IC0_F0TG_MB_C_brd_V02_OCP.brd

J37  SCONN288_DDR506112002KQ  IO  pkg DDR288S_1-1VXC  page 109
  VIN_BULK0  = P12V_MEM_CPU1
  RFU0  = NC
  VIN_MGMT  = P3V3_AUX
  HSCL  = I3C_SPD_DDRL_CPU1_SCL
  HSDA  = I3C_SPD_DDRL_CPU1_SDA
  VSS0  = GND
  DQ0_A  = M_L_CPU1_SA_DQ<0>
  VSS1  = GND
  DQ1_A  = M_L_CPU1_SA_DQ<1>
  VSS2  = GND
  DQS0_A_T  = M_L_CPU1_SA_DQS_DP<0>
  DQS0_A_C  = M_L_CPU1_SA_DQS_DN<0>
  VSS3  = GND
  DQ4_A  = M_L_CPU1_SA_DQ<4>
  VSS4  = GND
  DQ5_A  = M_L_CPU1_SA_DQ<5>
  VSS5  = GND
  DQ8_A  = M_L_CPU1_SA_DQ<8>
  VSS6  = GND
  DQ9_A  = M_L_CPU1_SA_DQ<9>
  VSS7  = GND
  DQS1_A_T  = M_L_CPU1_SA_DQS_DP<1>
  DQS1_A_C  = M_L_CPU1_SA_DQS_DN<1>
  VSS8  = GND
  DQ12_A  = M_L_CPU1_SA_DQ<12>
  VSS9  = GND
  DQ13_A  = M_L_CPU1_SA_DQ<13>
  VSS10  = GND
  DQ16_A  = M_L_CPU1_SA_DQ<16>
  VSS11  = GND
  DQ17_A  = M_L_CPU1_SA_DQ<17>
  VSS12  = GND
  DQS2_A_T  = M_L_CPU1_SA_DQS_DP<2>
  DQS2_A_C  = M_L_CPU1_SA_DQS_DN<2>
  VSS13  = GND
  DQ20_A  = M_L_CPU1_SA_DQ<20>
  VSS14  = GND
  DQ21_A  = M_L_CPU1_SA_DQ<21>
  VSS15  = GND
  DQ24_A  = M_L_CPU1_SA_DQ<24>
  VSS16  = GND
  DQ25_A  = M_L_CPU1_SA_DQ<25>
  VSS17  = GND
  DQS3_A_T  = M_L_CPU1_SA_DQS_DP<3>
  DQS3_A_C  = M_L_CPU1_SA_DQS_DN<3>
  VSS18  = GND
  DQ28_A  = M_L_CPU1_SA_DQ<28>
  VSS19  = GND
  DQ29_A  = M_L_CPU1_SA_DQ<29>
  VSS20  = GND
  CB0_A  = M_L_CPU1_SA_CB<0>
  VSS21  = GND
  CB1_A  = M_L_CPU1_SA_CB<1>
  VSS22  = GND
  DQS4_A_T  = M_L_CPU1_SA_DQS_DP<4>
  DQS4_A_C  = M_L_CPU1_SA_DQS_DN<4>
  VSS23  = GND
  CB4_A  = M_L_CPU1_SA_CB<4>
  VSS24  = GND
  CB5_A  = M_L_CPU1_SA_CB<5>
  VSS25  = GND
  ALERT_N  = M_L_CPU1_ALERT_N
  VSS26  = GND
  CS0_A_N  = M_L_CPU1_SA_CS_N<0>
  VSS27  = GND
  CA0_A  = M_L_CPU1_SA_CA<0>
  VSS28  = GND
  CA2_A  = M_L_CPU1_SA_CA<2>
  VSS29  = GND
  CA4_A  = M_L_CPU1_SA_CA<4>
  VSS30  = GND
  CA6_A  = M_L_CPU1_SA_CA<6>
  VSS31  = GND
  PAR_A  = M_L_CPU1_SA_PAR
  VSS32  = GND
  CA0_B  = M_L_CPU1_SB_CA<0>
  VSS33  = GND
  CA2_B  = M_L_CPU1_SB_CA<2>
  VSS34  = GND
  CA4_B  = M_L_CPU1_SB_CA<4>
  VSS35  = GND
  CA6_B  = M_L_CPU1_SB_CA<6>
  VSS36  = GND
  CS0_B_N  = M_L_CPU1_SB_CS_N<0>
  VSS37  = GND
  \lbd||rsp_a_n\  = M_L_CPU1_SA_RSP<0>
  \lbs||rsp_b_n\  = M_L_CPU1_SB_RSP<0>
  VSS38  = GND
  CB4_B  = M_L_CPU1_SB_CB<4>
  VSS39  = GND
  CB5_B  = M_L_CPU1_SB_CB<5>
  VSS40  = GND
  \dqs9_b_t||tdqs9_b_t||dbi4_b_n\  = M_L_CPU1_SB_DQS_DP<9>
  \dqs9_b_c||tdqs9_b_c\  = M_L_CPU1_SB_DQS_DN<9>
  VSS41  = GND
  CB0_B  = M_L_CPU1_SB_CB<0>
  VSS42  = GND
  CB1_B  = M_L_CPU1_SB_CB<1>
  VSS43  = GND
  DQ0_B  = M_L_CPU1_SB_DQ<0>
  VSS44  = GND
  DQ1_B  = M_L_CPU1_SB_DQ<1>
  VSS45  = GND
  DQS0_B_T  = M_L_CPU1_SB_DQS_DP<0>
  DQS0_B_C  = M_L_CPU1_SB_DQS_DN<0>
  VSS46  = GND
  DQ4_B  = M_L_CPU1_SB_DQ<4>
  VSS47  = GND
  DQ5_B  = M_L_CPU1_SB_DQ<5>
  VSS48  = GND
  DQ8_B  = M_L_CPU1_SB_DQ<8>
  VSS49  = GND
  DQ9_B  = M_L_CPU1_SB_DQ<9>
  VSS50  = GND
  DQS1_B_T  = M_L_CPU1_SB_DQS_DP<1>
  DQS1_B_C  = M_L_CPU1_SB_DQS_DN<1>
  VSS51  = GND
  DQ12_B  = M_L_CPU1_SB_DQ<12>
  VSS52  = GND
  DQ13_B  = M_L_CPU1_SB_DQ<13>
  VSS53  = GND
  DQ16_B  = M_L_CPU1_SB_DQ<16>
  VSS54  = GND
  DQ17_B  = M_L_CPU1_SB_DQ<17>
  VSS55  = GND
  DQS2_B_T  = M_L_CPU1_SB_DQS_DP<2>
  DQS2_B_C  = M_L_CPU1_SB_DQS_DN<2>
  VSS56  = GND
  DQ20_B  = M_L_CPU1_SB_DQ<20>
  VSS57  = GND
  DQ21_B  = M_L_CPU1_SB_DQ<21>
  VSS58  = GND
  DQ24_B  = M_L_CPU1_SB_DQ<24>
  VSS59  = GND
  DQ25_B  = M_L_CPU1_SB_DQ<25>
  VSS60  = GND
  DQS3_B_T  = M_L_CPU1_SB_DQS_DP<3>
  DQS3_B_C  = M_L_CPU1_SB_DQS_DN<3>
  VSS61  = GND
  DQ28_B  = M_L_CPU1_SB_DQ<28>
  VSS62  = GND
  DQ29_B  = M_L_CPU1_SB_DQ<29>
  VSS63  = GND
  RFU1  = NC
  VIN_BULK1  = P12V_MEM_CPU1
  VIN_BULK2  = P12V_MEM_CPU1
  \pwr_good||fail_n\  = PWRGD_CHL_CPU1_DIMM
  HAS  = PD_CHL_CPU1_DIMM_SAA
  RFU2  = NC
  RFU3  = NC
  VSS64  = GND
  DQ2_A  = M_L_CPU1_SA_DQ<2>
  VSS65  = GND
  DQ3_A  = M_L_CPU1_SA_DQ<3>
  VSS66  = GND
  \dqs5_a_c||tdqs5_a_c||dqs5_a_t||tdqs5_a_t\  = M_L_CPU1_SA_DQS_DN<5>
  \dqs5_a_t||tdqs5_a_t\  = M_L_CPU1_SA_DQS_DP<5>
  VSS67  = GND
  DQ6_A  = M_L_CPU1_SA_DQ<6>
  VSS68  = GND
  DQ7_A  = M_L_CPU1_SA_DQ<7>
  VSS69  = GND
  DQ10_A  = M_L_CPU1_SA_DQ<10>
  VSS70  = GND
  DQ11_A  = M_L_CPU1_SA_DQ<11>
  VSS71  = GND
  \dqs6_a_c||tdqs6_a_c||dqs6_a_t||tdqs6_a_t\  = M_L_CPU1_SA_DQS_DN<6>
  \dqs6_a_t||tdqs6_a_t\  = M_L_CPU1_SA_DQS_DP<6>
  VSS72  = GND
  DQ14_A  = M_L_CPU1_SA_DQ<14>
  VSS73  = GND
  DQ15_A  = M_L_CPU1_SA_DQ<15>
  VSS74  = GND
  DQ18_A  = M_L_CPU1_SA_DQ<18>
  VSS75  = GND
  DQ19_A  = M_L_CPU1_SA_DQ<19>
  VSS76  = GND
  \dqs7_a_c||tdqs7_a_c\  = M_L_CPU1_SA_DQS_DN<7>
  \dqs7_a_t||tdqs7_a_t\  = M_L_CPU1_SA_DQS_DP<7>
  VSS77  = GND
  DQ22_A  = M_L_CPU1_SA_DQ<22>
  VSS78  = GND
  DQ23_A  = M_L_CPU1_SA_DQ<23>
  VSS79  = GND
  DQ26_A  = M_L_CPU1_SA_DQ<26>
  VSS80  = GND
  DQ27_A  = M_L_CPU1_SA_DQ<27>
  VSS81  = GND
  \dqs8_a_c||tdqs8_a_c\  = M_L_CPU1_SA_DQS_DN<8>
  \dqs8_a_t||tdqs8_a_t\  = M_L_CPU1_SA_DQS_DP<8>
  VSS82  = GND
  DQ30_A  = M_L_CPU1_SA_DQ<30>
  VSS83  = GND
  DQ31_A  = M_L_CPU1_SA_DQ<31>
  VSS84  = GND
  CB2_A  = M_L_CPU1_SA_CB<2>
  VSS85  = GND
  CB3_A  = M_L_CPU1_SA_CB<3>
  VSS86  = GND
  \dqs9_a_c||tdqs9_a_c\  = M_L_CPU1_SA_DQS_DN<9>
  \dqs9_a_t||tdqs9_a_t\  = M_L_CPU1_SA_DQS_DP<9>
  VSS87  = GND
  CB6_A  = M_L_CPU1_SA_CB<6>
  VSS88  = GND
  CB7_A  = M_L_CPU1_SA_CB<7>
  VSS89  = GND
  RESET_N  = M_L_CPU1_RESET_N
  VSS90  = GND
  CS1_A_N  = M_L_CPU1_SA_CS_N<1>
  VSS91  = GND
  CA1_A  = M_L_CPU1_SA_CA<1>
  VSS92  = GND
  CA3_A  = M_L_CPU1_SA_CA<3>
  VSS93  = GND
  CA5_A  = M_L_CPU1_SA_CA<5>
  VSS94  = GND
  CK_T  = M_L_CPU1_CLK_DP<0>
  CK_C  = M_L_CPU1_CLK_DN<0>
  VSS95  = GND
  RFU4  = NC
  CA1_B  = M_L_CPU1_SB_CA<1>
  VSS96  = GND
  CA3_B  = M_L_CPU1_SB_CA<3>
  VSS97  = GND
  CA5_B  = M_L_CPU1_SB_CA<5>
  VSS98  = GND
  PAR_B  = M_L_CPU1_SB_PAR
  VSS99  = GND
  CS1_B_N  = M_L_CPU1_SB_CS_N<1>
  VSS100  = GND
  RFU5  = NC
  RFU6  = NC
  VSS101  = GND
  CB6_B  = M_L_CPU1_SB_CB<6>
  VSS102  = GND
  CB7_B  = M_L_CPU1_SB_CB<7>
  VSS103  = GND
  DQS4_B_C  = M_L_CPU1_SB_DQS_DN<4>
  DQS4_B_T  = M_L_CPU1_SB_DQS_DP<4>
  VSS104  = GND
  CB2_B  = M_L_CPU1_SB_CB<2>
  VSS105  = GND
  CB3_B  = M_L_CPU1_SB_CB<3>
  VSS106  = GND
  DQ2_B  = M_L_CPU1_SB_DQ<2>
  VSS107  = GND
  DQ3_B  = M_L_CPU1_SB_DQ<3>
  VSS108  = GND
  \dqs5_b_c||tdqs5_b_c\  = M_L_CPU1_SB_DQS_DN<5>
  \dqs5_b_t||tdqs5_b_t\  = M_L_CPU1_SB_DQS_DP<5>
  VSS109  = GND
  DQ6_B  = M_L_CPU1_SB_DQ<6>
  VSS110  = GND
  DQ7_B  = M_L_CPU1_SB_DQ<7>
  VSS111  = GND
  DQ10_B  = M_L_CPU1_SB_DQ<10>
  VSS112  = GND
  DQ11_B  = M_L_CPU1_SB_DQ<11>
  VSS113  = GND
  \dqs6_b_c||tdqs6_b_c\  = M_L_CPU1_SB_DQS_DN<6>
  \dqs6_b_t||tdqs6_b_t\  = M_L_CPU1_SB_DQS_DP<6>
  VSS114  = GND
  DQ14_B  = M_L_CPU1_SB_DQ<14>
  VSS115  = GND
  DQ15_B  = M_L_CPU1_SB_DQ<15>
  VSS116  = GND
  DQ18_B  = M_L_CPU1_SB_DQ<18>
  VSS117  = GND
  DQ19_B  = M_L_CPU1_SB_DQ<19>
  VSS118  = GND
  \dqs7_b_c||tdqs7_b_c\  = M_L_CPU1_SB_DQS_DN<7>
  \dqs7_b_t||tdqs7_b_t\  = M_L_CPU1_SB_DQS_DP<7>
  VSS119  = GND
  DQ22_B  = M_L_CPU1_SB_DQ<22>
  VSS120  = GND
  DQ23_B  = M_L_CPU1_SB_DQ<23>
  VSS121  = GND
  DQ26_B  = M_L_CPU1_SB_DQ<26>
  VSS122  = GND
  DQ27_B  = M_L_CPU1_SB_DQ<27>
  VSS123  = GND
  \dqs8_b_c||tdqs8_b_c\  = M_L_CPU1_SB_DQS_DN<8>
  \dqs8_b_t||tdqs8_b_t\  = M_L_CPU1_SB_DQS_DP<8>
  VSS124  = GND
  DQ30_B  = M_L_CPU1_SB_DQ<30>
  VSS125  = GND
  DQ31_B  = M_L_CPU1_SB_DQ<31>
  VSS126  = GND
  G1  = GND
  G2  = GND
  G3  = GND

(kicad_pcb
	(version 20260206)
	(generator "pcbnew")
	(generator_version "10.0")
	(general
		(thickness 1.6)
		(legacy_teardrops no)
	)
	(paper "A4")
	(title_block
		(title "04192023_DAF0TMB3IC0_F0TG_MB_C_brd_V02_OCP.brd")
		(comment 1 "Grand Teton / footprint 34 of 8354 (J37), pads 185-230 of 291")
	)
	(layers
		(0 "F.Cu" signal "TOP")
		(4 "In1.Cu" signal "GND")
		(6 "In2.Cu" signal "IN1")
		(8 "In3.Cu" signal "GND1")
		(10 "In4.Cu" signal "IN2")
		(12 "In5.Cu" signal "GND2")
		(14 "In6.Cu" signal "IN3")
		(16 "In7.Cu" signal "GND3")
		(18 "In8.Cu" signal "VCC")
		(20 "In9.Cu" signal "VCC1")
		(22 "In10.Cu" signal "GND4")
		(24 "In11.Cu" signal "IN4")
		(26 "In12.Cu" signal "GND5")
		(28 "In13.Cu" signal "IN5")
		(30 "In14.Cu" signal "GND6")
		(32 "In15.Cu" signal "IN6")
		(34 "In16.Cu" signal "GND7")
		(2 "B.Cu" signal "BOTTOM")
		(9 "F.Adhes" user "F.Adhesive")
		(11 "B.Adhes" user "B.Adhesive")
		(13 "F.Paste" user "Package Geometry/Pastemask Top")
		(15 "B.Paste" user "Package Geometry/Pastemask Bottom")
		(5 "F.SilkS" user "Ref Des/Silkscreen Top")
		(7 "B.SilkS" user "Ref Des/Silkscreen Bottom")
		(1 "F.Mask" user "Board Geometry/Soldermask Top")
		(3 "B.Mask" user "Board Geometry/Soldermask Bottom")
		(17 "Dwgs.User" user "User.Drawings")
		(19 "Cmts.User" user "User.Comments")
		(21 "Eco1.User" user "User.Eco1")
		(23 "Eco2.User" user "User.Eco2")
		(25 "Edge.Cuts" user "Board Geometry/Outline")
		(27 "Margin" user)
		(31 "F.CrtYd" user "Package Geometry/Place Bound Top")
		(29 "B.CrtYd" user "Package Geometry/Place Bound Bottom")
		(35 "F.Fab" user "Ref Des/Assembly Top")
		(33 "B.Fab" user "Ref Des/Assembly Bottom")
	)
	(footprint ""
		(layer "F.Cu")
		(at 204.197966 -255.560322 180)
		(property "Reference" "J37"
			(at 2.8702 -81.730088 0)
			(unlocked yes)
			(layer "F.SilkS")
			(effects
				(font
					(size 0.7874 0.5842)
					(thickness 0.1524)
				)
			)
		)
		(property "Value" ""
			(at 0 0 180)
			(layer "F.Fab")
			(effects
				(font
					(size 1.27 1.27)
				)
			)
		)
		(duplicate_pad_numbers_are_jumpers no)
		(pad "185" smd rect
			(at 2.050034 -29.325062 90)
			(size 0.519938 1.4986)
			(layers "F.Cu" "F.Mask" "F.Paste")
			(net "M_L_CPU1_SA_DQ<26>")
		)
		(pad "186" smd rect
			(at 2.050034 -28.474924 90)
			(size 0.519938 1.4986)
			(layers "F.Cu" "F.Mask" "F.Paste")
			(net "GND")
		)
		(pad "187" smd rect
			(at 2.050034 -27.62504 90)
			(size 0.519938 1.4986)
			(layers "F.Cu" "F.Mask" "F.Paste")
			(net "M_L_CPU1_SA_DQ<27>")
		)
		(pad "188" smd rect
			(at 2.050034 -26.774902 90)
			(size 0.519938 1.4986)
			(layers "F.Cu" "F.Mask" "F.Paste")
			(net "GND")
		)
		(pad "189" smd rect
			(at 2.050034 -25.925018 90)
			(size 0.519938 1.4986)
			(layers "F.Cu" "F.Mask" "F.Paste")
			(net "M_L_CPU1_SA_DQS_DN<8>")
		)
		(pad "190" smd rect
			(at 2.050034 -25.07488 90)
			(size 0.519938 1.4986)
			(layers "F.Cu" "F.Mask" "F.Paste")
			(net "M_L_CPU1_SA_DQS_DP<8>")
		)
		(pad "191" smd rect
			(at 2.050034 -24.224996 90)
			(size 0.519938 1.4986)
			(layers "F.Cu" "F.Mask" "F.Paste")
			(net "GND")
		)
		(pad "192" smd rect
			(at 2.050034 -23.375112 90)
			(size 0.519938 1.4986)
			(layers "F.Cu" "F.Mask" "F.Paste")
			(net "M_L_CPU1_SA_DQ<30>")
		)
		(pad "193" smd rect
			(at 2.050034 -22.524974 90)
			(size 0.519938 1.4986)
			(layers "F.Cu" "F.Mask" "F.Paste")
			(net "GND")
		)
		(pad "194" smd rect
			(at 2.050034 -21.67509 90)
			(size 0.519938 1.4986)
			(layers "F.Cu" "F.Mask" "F.Paste")
			(net "M_L_CPU1_SA_DQ<31>")
		)
		(pad "195" smd rect
			(at 2.050034 -20.824952 90)
			(size 0.519938 1.4986)
			(layers "F.Cu" "F.Mask" "F.Paste")
			(net "GND")
		)
		(pad "196" smd rect
			(at 2.050034 -19.975068 90)
			(size 0.519938 1.4986)
			(layers "F.Cu" "F.Mask" "F.Paste")
			(net "M_L_CPU1_SA_CB<2>")
		)
		(pad "197" smd rect
			(at 2.050034 -19.12493 90)
			(size 0.519938 1.4986)
			(layers "F.Cu" "F.Mask" "F.Paste")
			(net "GND")
		)
		(pad "198" smd rect
			(at 2.050034 -18.275046 90)
			(size 0.519938 1.4986)
			(layers "F.Cu" "F.Mask" "F.Paste")
			(net "M_L_CPU1_SA_CB<3>")
		)
		(pad "199" smd rect
			(at 2.050034 -17.424908 90)
			(size 0.519938 1.4986)
			(layers "F.Cu" "F.Mask" "F.Paste")
			(net "GND")
		)
		(pad "200" smd rect
			(at 2.050034 -16.575024 90)
			(size 0.519938 1.4986)
			(layers "F.Cu" "F.Mask" "F.Paste")
			(net "M_L_CPU1_SA_DQS_DN<9>")
		)
		(pad "201" smd rect
			(at 2.050034 -15.724886 90)
			(size 0.519938 1.4986)
			(layers "F.Cu" "F.Mask" "F.Paste")
			(net "M_L_CPU1_SA_DQS_DP<9>")
		)
		(pad "202" smd rect
			(at 2.050034 -14.875002 90)
			(size 0.519938 1.4986)
			(layers "F.Cu" "F.Mask" "F.Paste")
			(net "GND")
		)
		(pad "203" smd rect
			(at 2.050034 -14.025118 90)
			(size 0.519938 1.4986)
			(layers "F.Cu" "F.Mask" "F.Paste")
			(net "M_L_CPU1_SA_CB<6>")
		)
		(pad "204" smd rect
			(at 2.050034 -13.17498 90)
			(size 0.519938 1.4986)
			(layers "F.Cu" "F.Mask" "F.Paste")
			(net "GND")
		)
		(pad "205" smd rect
			(at 2.050034 -12.325096 90)
			(size 0.519938 1.4986)
			(layers "F.Cu" "F.Mask" "F.Paste")
			(net "M_L_CPU1_SA_CB<7>")
		)
		(pad "206" smd rect
			(at 2.050034 -11.474958 90)
			(size 0.519938 1.4986)
			(layers "F.Cu" "F.Mask" "F.Paste")
			(net "GND")
		)
		(pad "207" smd rect
			(at 2.050034 -10.625074 90)
			(size 0.519938 1.4986)
			(layers "F.Cu" "F.Mask" "F.Paste")
			(net "M_L_CPU1_RESET_N")
		)
		(pad "208" smd rect
			(at 2.050034 -9.774936 90)
			(size 0.519938 1.4986)
			(layers "F.Cu" "F.Mask" "F.Paste")
			(net "GND")
		)
		(pad "209" smd rect
			(at 2.050034 -8.925052 90)
			(size 0.519938 1.4986)
			(layers "F.Cu" "F.Mask" "F.Paste")
			(net "M_L_CPU1_SA_CS_N<1>")
		)
		(pad "210" smd rect
			(at 2.050034 -8.074914 90)
			(size 0.519938 1.4986)
			(layers "F.Cu" "F.Mask" "F.Paste")
			(net "GND")
		)
		(pad "211" smd rect
			(at 2.050034 -7.22503 90)
			(size 0.519938 1.4986)
			(layers "F.Cu" "F.Mask" "F.Paste")
			(net "M_L_CPU1_SA_CA<1>")
		)
		(pad "212" smd rect
			(at 2.050034 -6.374892 90)
			(size 0.519938 1.4986)
			(layers "F.Cu" "F.Mask" "F.Paste")
			(net "GND")
		)
		(pad "213" smd rect
			(at 2.050034 -5.525008 90)
			(size 0.519938 1.4986)
			(layers "F.Cu" "F.Mask" "F.Paste")
			(net "M_L_CPU1_SA_CA<3>")
		)
		(pad "214" smd rect
			(at 2.050034 -4.675124 90)
			(size 0.519938 1.4986)
			(layers "F.Cu" "F.Mask" "F.Paste")
			(net "GND")
		)
		(pad "215" smd rect
			(at 2.050034 -3.824986 90)
			(size 0.519938 1.4986)
			(layers "F.Cu" "F.Mask" "F.Paste")
			(net "M_L_CPU1_SA_CA<5>")
		)
		(pad "216" smd rect
			(at 2.050034 -2.975102 90)
			(size 0.519938 1.4986)
			(layers "F.Cu" "F.Mask" "F.Paste")
			(net "GND")
		)
		(pad "217" smd rect
			(at 2.050034 -2.124964 90)
			(size 0.519938 1.4986)
			(layers "F.Cu" "F.Mask" "F.Paste")
			(net "M_L_CPU1_CLK_DP<0>")
		)
		(pad "218" smd rect
			(at 2.050034 -1.27508 90)
			(size 0.519938 1.4986)
			(layers "F.Cu" "F.Mask" "F.Paste")
			(net "M_L_CPU1_CLK_DN<0>")
		)
		(pad "219" smd rect
			(at 2.050034 -0.424942 90)
			(size 0.519938 1.4986)
			(layers "F.Cu" "F.Mask" "F.Paste")
			(net "GND")
		)
		(pad "220" smd rect
			(at 2.050034 5.525008 90)
			(size 0.519938 1.4986)
			(layers "F.Cu" "F.Mask" "F.Paste")
			(net "Net_2414")
		)
		(pad "221" smd rect
			(at 2.050034 6.374892 90)
			(size 0.519938 1.4986)
			(layers "F.Cu" "F.Mask" "F.Paste")
			(net "M_L_CPU1_SB_CA<1>")
		)
		(pad "222" smd rect
			(at 2.050034 7.22503 90)
			(size 0.519938 1.4986)
			(layers "F.Cu" "F.Mask" "F.Paste")
			(net "GND")
		)
		(pad "223" smd rect
			(at 2.050034 8.074914 90)
			(size 0.519938 1.4986)
			(layers "F.Cu" "F.Mask" "F.Paste")
			(net "M_L_CPU1_SB_CA<3>")
		)
		(pad "224" smd rect
			(at 2.050034 8.925052 90)
			(size 0.519938 1.4986)
			(layers "F.Cu" "F.Mask" "F.Paste")
			(net "GND")
		)
		(pad "225" smd rect
			(at 2.050034 9.774936 90)
			(size 0.519938 1.4986)
			(layers "F.Cu" "F.Mask" "F.Paste")
			(net "M_L_CPU1_SB_CA<5>")
		)
		(pad "226" smd rect
			(at 2.050034 10.625074 90)
			(size 0.519938 1.4986)
			(layers "F.Cu" "F.Mask" "F.Paste")
			(net "GND")
		)
		(pad "227" smd rect
			(at 2.050034 11.474958 90)
			(size 0.519938 1.4986)
			(layers "F.Cu" "F.Mask" "F.Paste")
			(net "M_L_CPU1_SB_PAR")
		)
		(pad "228" smd rect
			(at 2.050034 12.325096 90)
			(size 0.519938 1.4986)
			(layers "F.Cu" "F.Mask" "F.Paste")
			(net "GND")
		)
		(pad "229" smd rect
			(at 2.050034 13.17498 90)
			(size 0.519938 1.4986)
			(layers "F.Cu" "F.Mask" "F.Paste")
			(net "M_L_CPU1_SB_CS_N<1>")
		)
		(pad "230" smd rect
			(at 2.050034 14.025118 90)
			(size 0.519938 1.4986)
			(layers "F.Cu" "F.Mask" "F.Paste")
			(net "GND")
		)
	)
)
